FILE_TYPE = MULTI_PHYS_TABLE;

PART 'DIODE_TVS'

{========================================================================================}
:VALUE             | PART_TYPE | MATERIAL | PART_NUMBER    = STANDARD    | LIFECYCLE     | PART_NUMBER   | JEDEC_TYPE             | DESCRIPTION                               | MANUFTR | MANUF_PN          | RD_CMPLS_LVL | CMPLS_LVL | CLASS | DIP_SMD | FP_ECN             | FROM_PJ       | DATA                      | EE_CHECK_LIST | STATUS | PSL | PREFERENCE | CREATOR | CREATEDAY  ;
{========================================================================================}
 'SMF13A'          | 'SMLF'    | 'IC'     | 'BC00013AZ00'(!) = ''          | ''            | 'BC00013AZ00' |'SOD123F'| 'DIODE SMD SMF13A(13V,9.3A)SOD-123F'      | 'LFI'   | 'SMF13A'          | 'EP(V1)'     | ''        | 'IC'  | ''      | ''                 | 'JBE-CH'      | 'LFI_SMF13A.pdf'          | ''            | ''     | ''  | ''         | ''      | '20160223'
 'SMF13A'          | 'SMLF'    | 'EMPTY'  | 'BC00013AZ00'(!) = ''          | ''            | 'BC00013AZ00' |'SOD123F'| 'DIODE SMD SMF13A(13V,9.3A)SOD-123F'      | 'LFI'   | 'SMF13A'          | 'EP(V1)'     | ''        | 'IC'  | ''      | ''                 | 'JBE-CH'      | 'LFI_SMF13A.pdf'          | ''            | ''     | ''  | ''         | ''      | '20160223'
 'SMF13A'          | 'SMLF'    | 'IC'     | 'BCSMF13AZ01'(!) = ''          | ''            | 'BCSMF13AZ01' |'SOD123FL_2-8X1-8'| 'DIODE SMD SMF13A(13V,9.3A)SOD-123FL'     | 'PJT'   | 'SMF13A'          | 'EP(V1)'     | ''        | 'IC'  | ''      | ''                 | 'JBE-CH'      | 'PJT_SMF13A.pdf'          | ''            | ''     | ''  | ''         | ''      | '20160223'
 'SMF13A'          | 'SMLF'    | 'EMPTY'  | 'BCSMF13AZ01'(!) = ''          | ''            | 'BCSMF13AZ01' |'SOD123FL_2-8X1-8'| 'DIODE SMD SMF13A(13V,9.3A)SOD-123FL'     | 'PJT'   | 'SMF13A'          | 'EP(V1)'     | ''        | 'IC'  | ''      | ''                 | 'JBE-CH'      | 'PJT_SMF13A.pdf'          | ''            | ''     | ''  | ''         | ''      | '20160223'
 'P4HE13A'         | 'SMLF'    | 'IC'     | 'BC4HE13AZ00'(!) = ''          | ''            | 'BC4HE13AZ00' |'SOD123HE_2-8X1-8'| 'DIODE SMD P4HE13A(13V,18.6A,400W)'       | 'PJT'   | 'P4HE13A'         | 'EP(V1)'     | ''        | 'IC'  | ''      | ''                 | 'JBE-CHARLES' | 'PJT_P4HE13A.pdf'         | ''            | ''     | ''  | ''         | ''      | '20160324'
 'P4HE13A'         | 'SMLF'    | 'EMPTY'  | 'BC4HE13AZ00'(!) = ''          | ''            | 'BC4HE13AZ00' |'SOD123HE_2-8X1-8'| 'DIODE SMD P4HE13A(13V,18.6A,400W)'       | 'PJT'   | 'P4HE13A'         | 'EP(V1)'     | ''        | 'IC'  | ''      | ''                 | 'JBE-CHARLES' | 'PJT_P4HE13A.pdf'         | ''            | ''     | ''  | ''         | ''      | '20160324'
 'SMDJ60A'         | 'SMLF'    | 'IC'     | 'BCSMDJ60Z00'(!) = ''          | ''            | 'BCSMDJ60Z00' |'D_SMDJ60A'| 'DIODE SMD SMDJ60A(60V,3000W)DO-214AB'    | 'LFI'   | 'SMDJ60A'         | 'EP(V1)'     | 'EP(V1)'  | 'IC'  | ''      | ''                 | 'T2M-JACK'    | 'LFI_SMDJ60A.pdf'         | ''            | ''     | ''  | ''         | ''      | '20170803'
 'SMDJ60A'         | 'SMLF'    | 'EMPTY'  | 'BCSMDJ60Z00'(!) = ''          | ''            | 'BCSMDJ60Z00' |'D_SMDJ60A'| 'DIODE SMD SMDJ60A(60V,3000W)DO-214AB'    | 'LFI'   | 'SMDJ60A'         | 'EP(V1)'     | 'EP(V1)'  | 'IC'  | ''      | ''                 | 'T2M-JACK'    | 'LFI_SMDJ60A.pdf'         | ''            | ''     | ''  | ''         | ''      | '20170803'
 'SMF14A'          | 'SMLF'    | 'IC'     | 'BCSMF14AZ01'(!) = ''          | ''            | 'BCSMF14AZ01' |'SOD123F'| 'DIODE SMF14A(14V,8.6A)SOD-123FL'         | 'LFI'   | 'SMF14A'          | 'EP(V1)'     | 'EP(V1)'  | 'IC'  | ''      | ''                 | 'F0G-EGBERT'  | 'LFI_SMF14A.pdf'          | ''            | ''     | ''  | ''         | ''      | '20190805'
 'SMF14A'          | 'SMLF'    | 'EMPTY'  | 'BCSMF14AZ01'(!) = ''          | ''            | 'BCSMF14AZ01' |'SOD123F'| 'DIODE SMF14A(14V,8.6A)SOD-123FL'         | 'LFI'   | 'SMF14A'          | 'EP(V1)'     | 'EP(V1)'  | 'IC'  | ''      | ''                 | 'F0G-EGBERT'  | 'LFI_SMF14A.pdf'          | ''            | ''     | ''  | ''         | ''      | '20190805'
 'DFLT14A-7'       | 'SMLF'    | 'IC'     | 'BCFLT14AZ00'(!) = ''          | ''            | 'BCFLT14AZ00' |'POWERDI123_ACXA'| 'DIODE TVS DFLT14A-7(14V,9.7A,225W)'      | 'DDS'   | 'DFLT14A-7'       | 'EP(V1)'     | ''        | 'IC'  | ''      | ''                 | 'F0G-EGBERT'  | 'DDS_DFLT14A-7.pdf'       | ''            | ''     | ''  | ''         | ''      | '20190924'
 'DFLT14A-7'       | 'SMLF'    | 'EMPTY'  | 'BCFLT14AZ00'(!) = ''          | ''            | 'BCFLT14AZ00' |'POWERDI123_ACXA'| 'DIODE TVS DFLT14A-7(14V,9.7A,225W)'      | 'DDS'   | 'DFLT14A-7'       | 'EP(V1)'     | ''        | 'IC'  | ''      | ''                 | 'F0G-EGBERT'  | 'DDS_DFLT14A-7.pdf'       | ''            | ''     | ''  | ''         | ''      | '20190924'
 'SMAJ14A'         | 'SMLF'    | 'IC'     | 'BCMAJ14AZ02'(!) = ''          | ''            | 'BCMAJ14AZ02' |'D1710_SMAXA'| 'DIODE TVS SMAJ14A(14V,17.2A,400W)'       | 'LFI'   | 'SMAJ14A'         | 'EP(V1)'     | ''        | 'IC'  | ''      | ''                 | 'F0G-EGBERT'  | 'LFI_SMAJ14A.pdf'         | ''            | ''     | ''  | ''         | ''      | '20190925'
 'SMAJ14A'         | 'SMLF'    | 'EMPTY'  | 'BCMAJ14AZ02'(!) = ''          | ''            | 'BCMAJ14AZ02' |'D1710_SMAXA'| 'DIODE TVS SMAJ14A(14V,17.2A,400W)'       | 'LFI'   | 'SMAJ14A'         | 'EP(V1)'     | ''        | 'IC'  | ''      | ''                 | 'F0G-EGBERT'  | 'LFI_SMAJ14A.pdf'         | ''            | ''     | ''  | ''         | ''      | '20190925'
 'SMF14A'          | 'SMLF'    | 'IC'     | 'BCSMF14AZ02'(!) = ''          | ''            | 'BCSMF14AZ02' |'SOD123FL_2-8X1-8'| 'DIODE TVS SMF14A(14V,20A,200W)'          | 'PJT'   | 'SMF14A'          | 'EP(V1)'     | ''        | 'IC'  | ''      | ''                 | 'F0G-EGBERT'  | 'PJT_SMF14A.pdf'          | ''            | ''     | ''  | ''         | ''      | '20200210'
 'SMF14A'          | 'SMLF'    | 'EMPTY'  | 'BCSMF14AZ02'(!) = ''          | ''            | 'BCSMF14AZ02' |'SOD123FL_2-8X1-8'| 'DIODE TVS SMF14A(14V,20A,200W)'          | 'PJT'   | 'SMF14A'          | 'EP(V1)'     | ''        | 'IC'  | ''      | ''                 | 'F0G-EGBERT'  | 'PJT_SMF14A.pdf'          | ''            | ''     | ''  | ''         | ''      | '20200210'
 '5.0SMDJ58A'      | 'SMLF'    | 'IC'     | 'BCMDJ58AZ01'(!) = ''          | ''            | 'BCMDJ58AZ01' |'D_SMDJ60A'| 'DIODE TVS 5.0SMDJ58A(58V,53.5A,5000W)'   | 'LFI'   | '5.0SMDJ58A'      | 'EP(V1)'     | ''        | 'IC'  | ''      | ''                 | 'S8A-YC'      | 'LFI_5.0SMDJ58A.pdf'      | ''            | ''     | ''  | ''         | ''      | '20200406'
 '5.0SMDJ58A'      | 'SMLF'    | 'EMPTY'  | 'BCMDJ58AZ01'(!) = ''          | ''            | 'BCMDJ58AZ01' |'D_SMDJ60A'| 'DIODE TVS 5.0SMDJ58A(58V,53.5A,5000W)'   | 'LFI'   | '5.0SMDJ58A'      | 'EP(V1)'     | ''        | 'IC'  | ''      | ''                 | 'S8A-YC'      | 'LFI_5.0SMDJ58A.pdf'      | ''            | ''     | ''  | ''         | ''      | '20200406'
 'SMAJ5.0A-13-F'   | 'SMLF'    | 'IC'     | 'BCMAJ50AZ00'(!) = ''          | ''            | 'BCMAJ50AZ00' |'D2010XF'| 'DIODE SMD SMAJ5.0A-13-F(5V,400W)SMA'     | 'DDS'   | 'SMAJ5.0A-13-F'   | 'EP(V1)'     | 'EP(V1)'  | 'IC'  | ''      | ''                 | 'IOX-EGBERT'  | 'DDS_SMAJ5.0A-13-F.pdf'   | ''            | ''     | ''  | ''         | ''      | '20200610'
 'SMAJ5.0A-13-F'   | 'SMLF'    | 'EMPTY'  | 'BCMAJ50AZ00'(!) = ''          | ''            | 'BCMAJ50AZ00' |'D2010XF'| 'DIODE SMD SMAJ5.0A-13-F(5V,400W)SMA'     | 'DDS'   | 'SMAJ5.0A-13-F'   | 'EP(V1)'     | 'EP(V1)'  | 'IC'  | ''      | ''                 | 'IOX-EGBERT'  | 'DDS_SMAJ5.0A-13-F.pdf'   | ''            | ''     | ''  | ''         | ''      | '20200610'
 'SMBJ14A-13-F'    | 'SMLF'    | 'IC'     | 'BCMBJ14AZ01'(!) = ''          | ''            | 'BCMBJ14AZ01' |'D_SMBJ14AXA'| 'DIODE TVS SMBJ14A-13-F(14V,25.8A,600W)'  | 'DDS'   | 'SMBJ14A-13-F'    | 'EP(V1)'     | ''        | 'IC'  | ''      | ''                 | 'IOX-EGBERT'  | 'DDS_SMBJ14A-13-F.pdf'    | ''            | ''     | ''  | ''         | ''      | '20200612'
 'SMBJ14A-13-F'    | 'SMLF'    | 'EMPTY'  | 'BCMBJ14AZ01'(!) = ''          | ''            | 'BCMBJ14AZ01' |'D_SMBJ14AXA'| 'DIODE TVS SMBJ14A-13-F(14V,25.8A,600W)'  | 'DDS'   | 'SMBJ14A-13-F'    | 'EP(V1)'     | ''        | 'IC'  | ''      | ''                 | 'IOX-EGBERT'  | 'DDS_SMBJ14A-13-F.pdf'    | ''            | ''     | ''  | ''         | ''      | '20200612'
 'SMBJ14A'         | 'SMLF'    | 'IC'     | 'BCMBJ14AZ00'(!) = ''          | ''            | 'BCMBJ14AZ00' |'D_SMBJ14A'| 'DIODE TVS SMBJ14A(14V,25.9A,600W)'       | 'LFI'   | 'SMBJ14A'         | 'EP(V1)'     | ''        | 'IC'  | ''      | ''                 | 'IOX-EGBERT'  | 'LFI_SMBJ14A.pdf'         | ''            | ''     | ''  | ''         | ''      | '20200616'
 'SMBJ14A'         | 'SMLF'    | 'EMPTY'  | 'BCMBJ14AZ00'(!) = ''          | ''            | 'BCMBJ14AZ00' |'D_SMBJ14A'| 'DIODE TVS SMBJ14A(14V,25.9A,600W)'       | 'LFI'   | 'SMBJ14A'         | 'EP(V1)'     | ''        | 'IC'  | ''      | ''                 | 'IOX-EGBERT'  | 'LFI_SMBJ14A.pdf'         | ''            | ''     | ''  | ''         | ''      | '20200616'
 'SMAJ5.0A'        | 'SMLF'    | 'IC'     | 'BCMAJ50AZ01'(!) = ''          | ''            | 'BCMAJ50AZ01' |'D1710_SMAXA'| 'DIODE TVS SMAJ5.0A(5V,43.5A,400W)'       | 'LFI'   | 'SMAJ5.0A'        | 'EP(V1)'     | ''        | 'IC'  | ''      | ''                 | 'F0CE-JAY'    | 'LFI_SMAJ5.0A.pdf'        | ''            | ''     | ''  | ''         | ''      | '20200620'
 'SMAJ5.0A'        | 'SMLF'    | 'EMPTY'  | 'BCMAJ50AZ01'(!) = ''          | ''            | 'BCMAJ50AZ01' |'D1710_SMAXA'| 'DIODE TVS SMAJ5.0A(5V,43.5A,400W)'       | 'LFI'   | 'SMAJ5.0A'        | 'EP(V1)'     | ''        | 'IC'  | ''      | ''                 | 'F0CE-JAY'    | 'LFI_SMAJ5.0A.pdf'        | ''            | ''     | ''  | ''         | ''      | '20200620'
 'P4SMAJ5.0A'      | 'SMLF'    | 'IC'     | 'BCMAJ50AZ02'(!) = ''          | ''            | 'BCMAJ50AZ02' |'D2010XH'| 'DIODE TVS P4SMAJ5.0A(5V,43.5A,400W)'     | 'PJT'   | 'P4SMAJ5.0A'      | 'EP(V1)'     | ''        | 'IC'  | ''      | ''                 | 'F0CE-JAY'    | 'PJT_P4SMAJ5.0A.pdf'      | ''            | ''     | ''  | ''         | ''      | '20200620'
 'P4SMAJ5.0A'      | 'SMLF'    | 'EMPTY'  | 'BCMAJ50AZ02'(!) = ''          | ''            | 'BCMAJ50AZ02' |'D2010XH'| 'DIODE TVS P4SMAJ5.0A(5V,43.5A,400W)'     | 'PJT'   | 'P4SMAJ5.0A'      | 'EP(V1)'     | ''        | 'IC'  | ''      | ''                 | 'F0CE-JAY'    | 'PJT_P4SMAJ5.0A.pdf'      | ''            | ''     | ''  | ''         | ''      | '20200620'
 'SMC5K14A-M3/I'   | 'SMLF'    | 'IC'     | 'BCC5K14AZ01'(!) = ''          | ''            | 'BCC5K14AZ01' |'D2723_SMCXK'| 'DIODE SMD SMC5K14A-M3/I(14V,216A)'       | 'SIL'   | 'SMC5K14A-M3/I'   | 'EP(V1)'     | ''        | 'IC'  | ''      | ''                 | 'F0CE-EGBERT' | 'SIL_SMC5K14A-M3I.pdf'    | ''            | ''     | ''  | ''         | ''      | '20200904'
 'SMC5K14A-M3/I'   | 'SMLF'    | 'EMPTY'  | 'BCC5K14AZ01'(!) = ''          | ''            | 'BCC5K14AZ01' |'D2723_SMCXK'| 'DIODE SMD SMC5K14A-M3/I(14V,216A)'       | 'SIL'   | 'SMC5K14A-M3/I'   | 'EP(V1)'     | ''        | 'IC'  | ''      | ''                 | 'F0CE-EGBERT' | 'SIL_SMC5K14A-M3I.pdf'    | ''            | ''     | ''  | ''         | ''      | '20200904'
 'P4SMAJ13AS'      | 'SMLF'    | 'IC'     | 'BCAJ13ASZ00'(!) = ''          | ''            | 'BCAJ13ASZ00' |'D2010XH'| 'DIODE SMD P4SMAJ13AS(13V,18.6A)'         | 'PJT'   | 'P4SMAJ13AS'      | 'EP(V1)'     | ''        | 'IC'  | ''      | ''                 | 'S3IS-MARK'   | 'PJT_P4SMAJ13AS.pdf'      | ''            | ''     | ''  | ''         | ''      | '20200908'
 'P4SMAJ13AS'      | 'SMLF'    | 'EMPTY'  | 'BCAJ13ASZ00'(!) = ''          | ''            | 'BCAJ13ASZ00' |'D2010XH'| 'DIODE SMD P4SMAJ13AS(13V,18.6A)'         | 'PJT'   | 'P4SMAJ13AS'      | 'EP(V1)'     | ''        | 'IC'  | ''      | ''                 | 'S3IS-MARK'   | 'PJT_P4SMAJ13AS.pdf'      | ''            | ''     | ''  | ''         | ''      | '20200908'
 'SMBJ58A'         | 'SMLF'    | 'IC'     | 'BC0MBJ58Z00'(!) = ''          | ''            | 'BC0MBJ58Z00' |'D_SMBJ14A'| 'DIODE SMD SMBJ58A(58V,6.5A)'             | 'LFI'   | 'SMBJ58A'         | 'EP(V1)'     | 'EP(V1)'  | 'IC'  | ''      | ''                 | 'P0A-STEVE'   | 'LFI_SMBJ58A.pdf'         | ''            | ''     | ''  | ''         | ''      | '20210304'
 'SMBJ58A'         | 'SMLF'    | 'EMPTY'  | 'BC0MBJ58Z00'(!) = ''          | ''            | 'BC0MBJ58Z00' |'D_SMBJ14A'| 'DIODE SMD SMBJ58A(58V,6.5A)'             | 'LFI'   | 'SMBJ58A'         | 'EP(V1)'     | 'EP(V1)'  | 'IC'  | ''      | ''                 | 'P0A-STEVE'   | 'LFI_SMBJ58A.pdf'         | ''            | ''     | ''  | ''         | ''      | '20210304'
 'SMDJ54A'         | 'SMLF'    | 'IC'     | 'BCMDJ54AZ00'(!) = ''          | ''            | 'BCMDJ54AZ00' |'D_SMDJ60A'| 'DIODE SMD SMDJ54A(54V,3000W)'            | 'LFI'   | 'SMDJ54A'         | 'EP(V1)'     | ''        | 'IC'  | ''      | ''                 | 'S7P-VINCENT' | 'LFI_SMDJ54A.pdf'         | ''            | ''     | ''  | ''         | ''      | '20210325'
 'SMDJ54A'         | 'SMLF'    | 'EMPTY'  | 'BCMDJ54AZ00'(!) = ''          | ''            | 'BCMDJ54AZ00' |'D_SMDJ60A'| 'DIODE SMD SMDJ54A(54V,3000W)'            | 'LFI'   | 'SMDJ54A'         | 'EP(V1)'     | ''        | 'IC'  | ''      | ''                 | 'S7P-VINCENT' | 'LFI_SMDJ54A.pdf'         | ''            | ''     | ''  | ''         | ''      | '20210325'
 '5.0SMDJ54A'      | 'SMLF'    | 'IC'     | 'BCMDJ54AZ01'(!) = ''          | ''            | 'BCMDJ54AZ01' |'D_SMDJ60A'| 'DIODE TVS 5.0SMDJ54A(54V,57.5A,5000W)'   | 'LFI'   | '5.0SMDJ54A'      | 'EP(V1)'     | ''        | 'IC'  | ''      | ''                 | 'S7P-VINCENT' | 'LFI_5.0SMDJ54A.pdf'      | ''            | ''     | ''  | ''         | ''      | '20210429'
 '5.0SMDJ54A'      | 'SMLF'    | 'EMPTY'  | 'BCMDJ54AZ01'(!) = ''          | ''            | 'BCMDJ54AZ01' |'D_SMDJ60A'| 'DIODE TVS 5.0SMDJ54A(54V,57.5A,5000W)'   | 'LFI'   | '5.0SMDJ54A'      | 'EP(V1)'     | ''        | 'IC'  | ''      | ''                 | 'S7P-VINCENT' | 'LFI_5.0SMDJ54A.pdf'      | ''            | ''     | ''  | ''         | ''      | '20210429'
 'AZ5413-01F.R7GR' | 'SMLF'    | 'IC'     | 'BC41301FZ00'(!) = ''          | ''            | 'BC41301FZ00' |'D0402_AZ5413-01FR7GR'| 'DIODE ESD AZ5413-01F.R7GR(3.3V,1UA,DFN)' | 'AMZ'   | 'AZ5413-01F.R7GR' | 'EP(V1)'     | 'EP(V1)'  | 'IC'  | ''      | ''                 | '2RE-JOHN'    | 'AMZ_AZ5413-01F.R7GR.pdf' | ''            | ''     | ''  | ''         | ''      | '20210511'
 'AZ5413-01F.R7GR' | 'SMLF'    | 'EMPTY'  | 'BC41301FZ00'(!) = ''          | ''            | 'BC41301FZ00' |'D0402_AZ5413-01FR7GR'| 'DIODE ESD AZ5413-01F.R7GR(3.3V,1UA,DFN)' | 'AMZ'   | 'AZ5413-01F.R7GR' | 'EP(V1)'     | 'EP(V1)'  | 'IC'  | ''      | ''                 | '2RE-JOHN'    | 'AMZ_AZ5413-01F.R7GR.pdf' | ''            | ''     | ''  | ''         | ''      | '20210511'
 '8.0SMDJ48A'      | 'SMLF'    | 'IC'     | 'BCMDJ48AZ00'(!) = ''          | ''            | 'BCMDJ48AZ00' |'D_SMDJ60A'| 'DIODE SMD 8.0SMDJ48A(48V)'               | 'LFI'   | '8.0SMDJ48A'      | 'EP(V1)'     | ''        | 'IC'  | ''      | ''                 | 'S1L-BERNIE'  | 'LFI_8.0SMDJ48A.pdf'      | ''            | ''     | ''  | ''         | ''      | '20210513'
 '8.0SMDJ48A'      | 'SMLF'    | 'EMPTY'  | 'BCMDJ48AZ00'(!) = ''          | ''            | 'BCMDJ48AZ00' |'D_SMDJ60A'| 'DIODE SMD 8.0SMDJ48A(48V)'               | 'LFI'   | '8.0SMDJ48A'      | 'EP(V1)'     | ''        | 'IC'  | ''      | ''                 | 'S1L-BERNIE'  | 'LFI_8.0SMDJ48A.pdf'      | ''            | ''     | ''  | ''         | ''      | '20210513'
 'SMAJ13A'         | 'SMLF'    | 'IC'     | 'BCMAJ13AZ04'(!) = ''          | ''            | 'BCMAJ13AZ04' |'D1710_SMAXA'| 'DIODE TVS SMAJ13A(14V,17.2A,400W)'       | 'LFI'   | 'SMAJ13A'         | 'EP(V1)'     | ''        | 'IC'  | ''      | ''                 | 'F0CE-SAM'    | 'LFI_SMAJ13A.pdf'         | ''            | ''     | ''  | ''         | ''      | '20210705'
 'SMAJ13A'         | 'SMLF'    | 'EMPTY'  | 'BCMAJ13AZ04'(!) = ''          | ''            | 'BCMAJ13AZ04' |'D1710_SMAXA'| 'DIODE TVS SMAJ13A(14V,17.2A,400W)'       | 'LFI'   | 'SMAJ13A'         | 'EP(V1)'     | ''        | 'IC'  | ''      | ''                 | 'F0CE-SAM'    | 'LFI_SMAJ13A.pdf'         | ''            | ''     | ''  | ''         | ''      | '20210705'
 'SMC5K13A-M3/I'   | 'SMLF'    | 'IC'     | 'BCC5K13AZ00'(!) = ''          | ''            | 'BCC5K13AZ00' |'D2723_SMCXK'| 'DIODE TVS SMC5K13A-M3/I(13V,216A)AEC'    | 'SIL'   | 'SMC5K13A-M3/I'   | 'EP(V1)'     | ''        | 'IC'  | ''      | 'SMC5K13A-M3I.msg' | 'F0CE-SAM'    | 'SIL_SMC5K13A-M3I.pdf'    | ''            | ''     | ''  | ''         | ''      | '20210705'
 'SMC5K13A-M3/I'   | 'SMLF'    | 'EMPTY'  | 'BCC5K13AZ00'(!) = ''          | ''            | 'BCC5K13AZ00' |'D2723_SMCXK'| 'DIODE TVS SMC5K13A-M3/I(13V,216A)AEC'    | 'SIL'   | 'SMC5K13A-M3/I'   | 'EP(V1)'     | ''        | 'IC'  | ''      | 'SMC5K13A-M3I.msg' | 'F0CE-SAM'    | 'SIL_SMC5K13A-M3I.pdf'    | ''            | ''     | ''  | ''         | ''      | '20210705'
 'SMBJ14A-M3/52'   | 'SMLF'    | 'IC'     | 'BCMBJ14AZ03'(!) = ''          | ''            | 'BCMBJ14AZ03' |'D_SMBJ14AXB'| 'DIODE SMBJ14A-M3/52(14V,25.9A)'          | 'SIL'   | 'SMBJ14A-M3/52'   | 'EP(V1)'     | ''        | 'IC'  | ''      | ''                 | 'F0CE-FRANK'  | 'SIL_SMBJ14A-M352.pdf'    | ''            | ''     | ''  | ''         | ''      | '20211026'
 'SMBJ14A-M3/52'   | 'SMLF'    | 'EMPTY'  | 'BCMBJ14AZ03'(!) = ''          | ''            | 'BCMBJ14AZ03' |'D_SMBJ14AXB'| 'DIODE SMBJ14A-M3/52(14V,25.9A)'          | 'SIL'   | 'SMBJ14A-M3/52'   | 'EP(V1)'     | ''        | 'IC'  | ''      | ''                 | 'F0CE-FRANK'  | 'SIL_SMBJ14A-M352.pdf'    | ''            | ''     | ''  | ''         | ''      | '20211026'
 '5KMC14AS'        | 'SMLF'    | 'IC'     | 'BCMC14ASZ00'(!) = ''          | ''            | 'BCMC14ASZ00' |'D2723_SMCXG'| 'DIODE SMD 5KMC14AS (5000W,14V)'          | 'PJT'   | '5KMC14AS'        | 'EP(V1)'     | ''        | 'IC'  | ''      | ''                 | 'F0T-PETER'   | 'PJT_5KMC14AS.pdf'        | ''            | ''     | ''  | ''         | ''      | '20221207'
 '5KMC14AS'        | 'SMLF'    | 'EMPTY'  | 'BCMC14ASZ00'(!) = ''          | ''            | 'BCMC14ASZ00' |'D2723_SMCXG'| 'DIODE SMD 5KMC14AS (5000W,14V)'          | 'PJT'   | '5KMC14AS'        | 'EP(V1)'     | ''        | 'IC'  | ''      | ''                 | 'F0T-PETER'   | 'PJT_5KMC14AS.pdf'        | ''            | ''     | ''  | ''         | ''      | '20221207'
 'SMF4L14A-7'      | 'SMLF'    | 'IC'     | 'BC04L14AZ00'(!) = ''               | ''               | 'BC04L14AZ00' |'DO-219AA_SMF'| 'DIODE SMD SMF4L14A-7 (14V, 400W)'        | 'DDS'   | 'SMF4L14A-7'      | 'EP(V1)'     | ''        | 'IC'  | ''      | ''                 | 'S8G-MICHAEL' | 'DDS_SMF4L14A-7.pdf'      | ''            | ''     | ''  | ''         | ''      | '20230323'
 'SMF4L14A-7'      | 'SMLF'    | 'EMPTY'  | 'BC04L14AZ00'(!) = ''               | ''               | 'BC04L14AZ00' |'DO-219AA_SMF'| 'DIODE SMD SMF4L14A-7 (14V, 400W)'        | 'DDS'   | 'SMF4L14A-7'      | 'EP(V1)'     | ''        | 'IC'  | ''      | ''                 | 'S8G-MICHAEL' | 'DDS_SMF4L14A-7.pdf'      | ''            | ''     | ''  | ''         | ''      | '20230323'

END_PART

END.

